(kicad_pcb
	(version 20260206)
	(generator "pcbnew")
	(generator_version "10.0")
	(general
		(thickness 1.6)
		(legacy_teardrops no)
	)
	(paper "A4")
	(title_block
		(title "netronome-mezz — pcbd0082-001_rev01_jul9_a.brd")
		(comment 1 "Open CloudServer (Microsoft) / footprints 584-584 of 714")
	)
	(layers
		(0 "F.Cu" signal "TOP")
		(4 "In1.Cu" signal "02_GND")
		(6 "In2.Cu" signal "03_SIG")
		(8 "In3.Cu" signal "04_SIG")
		(10 "In4.Cu" signal "05_GND")
		(12 "In5.Cu" signal "06_PWR1")
		(14 "In6.Cu" signal "07_SIG")
		(16 "In7.Cu" signal "08_SIG")
		(18 "In8.Cu" signal "09_GND")
		(2 "B.Cu" signal "BOTTOM")
		(9 "F.Adhes" user "F.Adhesive")
		(11 "B.Adhes" user "B.Adhesive")
		(13 "F.Paste" user "Package Geometry/Pastemask Top")
		(15 "B.Paste" user "Package Geometry/Pastemask Bottom")
		(5 "F.SilkS" user "Ref Des/Silkscreen Top")
		(7 "B.SilkS" user "Ref Des/Silkscreen Bottom")
		(1 "F.Mask" user "Board Geometry/Soldermask Top")
		(3 "B.Mask" user "Board Geometry/Soldermask Bottom")
		(17 "Dwgs.User" user "User.Drawings")
		(19 "Cmts.User" user "User.Comments")
		(21 "Eco1.User" user "User.Eco1")
		(23 "Eco2.User" user "User.Eco2")
		(25 "Edge.Cuts" user "Board Geometry/Outline")
		(27 "Margin" user)
		(31 "F.CrtYd" user "Package Geometry/Place Bound Top")
		(29 "B.CrtYd" user "Package Geometry/Place Bound Bottom")
		(35 "F.Fab" user "Ref Des/Assembly Top")
		(33 "B.Fab" user "Ref Des/Assembly Bottom")
		(45 "User.4" user "COMPVAL_TYPE_BOTTOM")
	)
	(footprint ""
		(layer "B.Cu")
		(at 77.851 16.256 90)
		(property "Reference" "U18"
			(at 5.2705 6.858 0)
			(unlocked yes)
			(layer "B.SilkS")
			(effects
				(font
					(size 1.27 0.9652)
					(thickness 0.1524)
				)
				(justify left mirror)
			)
		)
		(property "Value" ""
			(at 0 0 90)
			(layer "B.Fab")
			(effects
				(font
					(size 1.27 1.27)
				)
				(justify mirror)
			)
		)
		(property "Component Value" "VALUE"
			(at 0.399999 -9.402597 90)
			(unlocked yes)
			(layer "User.4")
			(effects
				(font
					(size 0.254 0.254)
					(thickness 0.000001)
				)
				(justify mirror)
			)
		)
		(property "Device Type" "MEMC0051"
			(at 5.909996 -11.648211 90)
			(unlocked yes)
			(layer "B.Fab")
			(hide yes)
			(effects
				(font
					(size 1.27 0.9652)
					(thickness 0.000001)
				)
				(justify left mirror)
			)
		)
		(duplicate_pad_numbers_are_jumpers no)
		(fp_line
			(start 4.499991 -7.000011)
			(end 4.499991 7.000011)
			(stroke
				(width 0.1524)
				(type default)
			)
			(layer "B.SilkS")
		)
		(fp_line
			(start -4.499991 -7.000011)
			(end 4.499991 -7.000011)
			(stroke
				(width 0.1524)
				(type default)
			)
			(layer "B.SilkS")
		)
		(fp_line
			(start 4.499991 -5.999988)
			(end 3.499993 -7.000011)
			(stroke
				(width 0.1524)
				(type default)
			)
			(layer "B.SilkS")
		)
		(fp_line
			(start 4.499991 7.000011)
			(end -4.499991 7.000011)
			(stroke
				(width 0.1524)
				(type default)
			)
			(layer "B.SilkS")
		)
		(fp_line
			(start -4.499991 7.000011)
			(end -4.499991 -7.000011)
			(stroke
				(width 0.1524)
				(type default)
			)
			(layer "B.SilkS")
		)
		(fp_poly
			(pts
				(xy 7.50001 10.000005) (xy -7.50001 10.000005) (xy -7.50001 -10.000005) (xy 7.50001 -10.000005)
			)
			(stroke
				(width 0)
				(type default)
			)
			(fill no)
			(layer "B.CrtYd")
		)
		(fp_line
			(start 4.499991 -7.000011)
			(end 4.499991 7.000011)
			(stroke
				(width 0.1)
				(type default)
			)
			(layer "B.Fab")
		)
		(fp_line
			(start -4.499991 -7.000011)
			(end 4.499991 -7.000011)
			(stroke
				(width 0.1)
				(type default)
			)
			(layer "B.Fab")
		)
		(fp_line
			(start 4.499991 -5.999988)
			(end 3.499993 -7.000011)
			(stroke
				(width 0.1)
				(type default)
			)
			(layer "B.Fab")
		)
		(fp_line
			(start 4.499991 7.000011)
			(end -4.499991 7.000011)
			(stroke
				(width 0.1)
				(type default)
			)
			(layer "B.Fab")
		)
		(fp_line
			(start -4.499991 7.000011)
			(end -4.499991 -7.000011)
			(stroke
				(width 0.1)
				(type default)
			)
			(layer "B.Fab")
		)
		(fp_text user "1"
			(at 3.40233 -7.493 0)
			(unlocked yes)
			(layer "B.SilkS")
			(effects
				(font
					(size 0.7874 0.5842)
					(thickness 0.127)
				)
				(justify mirror)
			)
		)
		(fp_text user "A"
			(at 5.18033 -5.842 0)
			(unlocked yes)
			(layer "B.SilkS")
			(effects
				(font
					(size 0.7874 0.5842)
					(thickness 0.127)
				)
				(justify mirror)
			)
		)
		(pad "A1" smd circle
			(at 3.199994 -5.999988 270)
			(size 0.3556 0.3556)
			(layers "B.Cu" "B.Mask" "B.Paste")
			(net "DDR_VDDQ")
		)
		(pad "A2" smd circle
			(at 2.399995 -5.999988 270)
			(size 0.3556 0.3556)
			(layers "B.Cu" "B.Mask" "B.Paste")
			(net "DDR0_32A_DQ24")
		)
		(pad "A3" smd circle
			(at 1.599997 -5.999988 270)
			(size 0.3556 0.3556)
			(layers "B.Cu" "B.Mask" "B.Paste")
			(net "DDR0_32A_DQ29")
		)
		(pad "A7" smd circle
			(at -1.599997 -5.999988 270)
			(size 0.3556 0.3556)
			(layers "B.Cu" "B.Mask" "B.Paste")
			(net "DDR0_32A_DQ26")
		)
		(pad "A8" smd circle
			(at -2.399995 -5.999988 270)
			(size 0.3556 0.3556)
			(layers "B.Cu" "B.Mask" "B.Paste")
			(net "DDR_VDDQ")
		)
		(pad "A9" smd circle
			(at -3.199994 -5.999988 270)
			(size 0.3556 0.3556)
			(layers "B.Cu" "B.Mask" "B.Paste")
			(net "GND")
		)
		(pad "B1" smd circle
			(at 3.199994 -5.19999 270)
			(size 0.3556 0.3556)
			(layers "B.Cu" "B.Mask" "B.Paste")
			(net "GND")
		)
		(pad "B2" smd circle
			(at 2.399995 -5.19999 270)
			(size 0.3556 0.3556)
			(layers "B.Cu" "B.Mask" "B.Paste")
			(net "DDR_VDDQ")
		)
		(pad "B3" smd circle
			(at 1.599997 -5.19999 270)
			(size 0.3556 0.3556)
			(layers "B.Cu" "B.Mask" "B.Paste")
			(net "GND")
		)
		(pad "B7" smd circle
			(at -1.599997 -5.19999 270)
			(size 0.3556 0.3556)
			(layers "B.Cu" "B.Mask" "B.Paste")
			(net "DDR0_32A_DQS3_N")
		)
		(pad "B8" smd circle
			(at -2.399995 -5.19999 270)
			(size 0.3556 0.3556)
			(layers "B.Cu" "B.Mask" "B.Paste")
			(net "DDR0_32A_DQ28")
		)
		(pad "B9" smd circle
			(at -3.199994 -5.19999 270)
			(size 0.3556 0.3556)
			(layers "B.Cu" "B.Mask" "B.Paste")
			(net "GND")
		)
		(pad "C1" smd circle
			(at 3.199994 -4.399991 270)
			(size 0.3556 0.3556)
			(layers "B.Cu" "B.Mask" "B.Paste")
			(net "DDR_VDDQ")
		)
		(pad "C2" smd circle
			(at 2.399995 -4.399991 270)
			(size 0.3556 0.3556)
			(layers "B.Cu" "B.Mask" "B.Paste")
			(net "DDR0_32A_DQ31")
		)
		(pad "C3" smd circle
			(at 1.599997 -4.399991 270)
			(size 0.3556 0.3556)
			(layers "B.Cu" "B.Mask" "B.Paste")
			(net "DDR0_32A_DQ30")
		)
		(pad "C7" smd circle
			(at -1.599997 -4.399991 270)
			(size 0.3556 0.3556)
			(layers "B.Cu" "B.Mask" "B.Paste")
			(net "DDR0_32A_DQS3_P")
		)
		(pad "C8" smd circle
			(at -2.399995 -4.399991 270)
			(size 0.3556 0.3556)
			(layers "B.Cu" "B.Mask" "B.Paste")
			(net "DDR0_32A_DQ25")
		)
		(pad "C9" smd circle
			(at -3.199994 -4.399991 270)
			(size 0.3556 0.3556)
			(layers "B.Cu" "B.Mask" "B.Paste")
			(net "DDR_VDDQ")
		)
		(pad "D1" smd circle
			(at 3.199994 -3.599993 270)
			(size 0.3556 0.3556)
			(layers "B.Cu" "B.Mask" "B.Paste")
			(net "GND")
		)
		(pad "D2" smd circle
			(at 2.399995 -3.599993 270)
			(size 0.3556 0.3556)
			(layers "B.Cu" "B.Mask" "B.Paste")
			(net "DDR_VDDQ")
		)
		(pad "D3" smd circle
			(at 1.599997 -3.599993 270)
			(size 0.3556 0.3556)
			(layers "B.Cu" "B.Mask" "B.Paste")
			(net "DDR0_32A_DM3")
		)
		(pad "D7" smd circle
			(at -1.599997 -3.599993 270)
			(size 0.3556 0.3556)
			(layers "B.Cu" "B.Mask" "B.Paste")
			(net "DDR0_32A_DQ27")
		)
		(pad "D8" smd circle
			(at -2.399995 -3.599993 270)
			(size 0.3556 0.3556)
			(layers "B.Cu" "B.Mask" "B.Paste")
			(net "GND")
		)
		(pad "D9" smd circle
			(at -3.199994 -3.599993 270)
			(size 0.3556 0.3556)
			(layers "B.Cu" "B.Mask" "B.Paste")
			(net "DDR_VDDQ")
		)
		(pad "E1" smd circle
			(at 3.199994 -2.799994 270)
			(size 0.3556 0.3556)
			(layers "B.Cu" "B.Mask" "B.Paste")
			(net "GND")
		)
		(pad "E2" smd circle
			(at 2.399995 -2.799994 270)
			(size 0.3556 0.3556)
			(layers "B.Cu" "B.Mask" "B.Paste")
			(net "GND")
		)
		(pad "E3" smd circle
			(at 1.599997 -2.799994 270)
			(size 0.3556 0.3556)
			(layers "B.Cu" "B.Mask" "B.Paste")
			(net "DDR0_32A_DQ16")
		)
		(pad "E7" smd circle
			(at -1.599997 -2.799994 270)
			(size 0.3556 0.3556)
			(layers "B.Cu" "B.Mask" "B.Paste")
			(net "DDR0_32A_DM2")
		)
		(pad "E8" smd circle
			(at -2.399995 -2.799994 270)
			(size 0.3556 0.3556)
			(layers "B.Cu" "B.Mask" "B.Paste")
			(net "GND")
		)
		(pad "E9" smd circle
			(at -3.199994 -2.799994 270)
			(size 0.3556 0.3556)
			(layers "B.Cu" "B.Mask" "B.Paste")
			(net "DDR_VDDQ")
		)
		(pad "F1" smd circle
			(at 3.199994 -1.999996 270)
			(size 0.3556 0.3556)
			(layers "B.Cu" "B.Mask" "B.Paste")
			(net "DDR_VDDQ")
		)
		(pad "F2" smd circle
			(at 2.399995 -1.999996 270)
			(size 0.3556 0.3556)
			(layers "B.Cu" "B.Mask" "B.Paste")
			(net "DDR0_32A_DQ21")
		)
		(pad "F3" smd circle
			(at 1.599997 -1.999996 270)
			(size 0.3556 0.3556)
			(layers "B.Cu" "B.Mask" "B.Paste")
			(net "DDR0_32A_DQS2_P")
		)
		(pad "F7" smd circle
			(at -1.599997 -1.999996 270)
			(size 0.3556 0.3556)
			(layers "B.Cu" "B.Mask" "B.Paste")
			(net "DDR0_32A_DQ18")
		)
		(pad "F8" smd circle
			(at -2.399995 -1.999996 270)
			(size 0.3556 0.3556)
			(layers "B.Cu" "B.Mask" "B.Paste")
			(net "DDR0_32A_DQ20")
		)
		(pad "F9" smd circle
			(at -3.199994 -1.999996 270)
			(size 0.3556 0.3556)
			(layers "B.Cu" "B.Mask" "B.Paste")
			(net "GND")
		)
		(pad "G1" smd circle
			(at 3.199994 -1.199998 270)
			(size 0.3556 0.3556)
			(layers "B.Cu" "B.Mask" "B.Paste")
			(net "GND")
		)
		(pad "G2" smd circle
			(at 2.399995 -1.199998 270)
			(size 0.3556 0.3556)
			(layers "B.Cu" "B.Mask" "B.Paste")
			(net "DDR0_32A_DQ17")
		)
		(pad "G3" smd circle
			(at 1.599997 -1.199998 270)
			(size 0.3556 0.3556)
			(layers "B.Cu" "B.Mask" "B.Paste")
			(net "DDR0_32A_DQS2_N")
		)
		(pad "G7" smd circle
			(at -1.599997 -1.199998 270)
			(size 0.3556 0.3556)
			(layers "B.Cu" "B.Mask" "B.Paste")
			(net "DDR_VDDQ")
		)
		(pad "G8" smd circle
			(at -2.399995 -1.199998 270)
			(size 0.3556 0.3556)
			(layers "B.Cu" "B.Mask" "B.Paste")
			(net "GND")
		)
		(pad "G9" smd circle
			(at -3.199994 -1.199998 270)
			(size 0.3556 0.3556)
			(layers "B.Cu" "B.Mask" "B.Paste")
			(net "GND")
		)
		(pad "H1" smd circle
			(at 3.199994 -0.399999 270)
			(size 0.3556 0.3556)
			(layers "B.Cu" "B.Mask" "B.Paste")
			(net "DDR0_32A_VREF1B")
		)
		(pad "H2" smd circle
			(at 2.399995 -0.399999 270)
			(size 0.3556 0.3556)
			(layers "B.Cu" "B.Mask" "B.Paste")
			(net "DDR_VDDQ")
		)
		(pad "H3" smd circle
			(at 1.599997 -0.399999 270)
			(size 0.3556 0.3556)
			(layers "B.Cu" "B.Mask" "B.Paste")
			(net "DDR0_32A_DQ19")
		)
		(pad "H7" smd circle
			(at -1.599997 -0.399999 270)
			(size 0.3556 0.3556)
			(layers "B.Cu" "B.Mask" "B.Paste")
			(net "DDR0_32A_DQ23")
		)
		(pad "H8" smd circle
			(at -2.399995 -0.399999 270)
			(size 0.3556 0.3556)
			(layers "B.Cu" "B.Mask" "B.Paste")
			(net "DDR0_32A_DQ22")
		)
		(pad "H9" smd circle
			(at -3.199994 -0.399999 270)
			(size 0.3556 0.3556)
			(layers "B.Cu" "B.Mask" "B.Paste")
			(net "DDR_VDDQ")
		)
		(pad "J1" smd circle
			(at 3.199994 0.399999 270)
			(size 0.3556 0.3556)
			(layers "B.Cu" "B.Mask" "B.Paste")
			(net "Net_92")
		)
		(pad "J2" smd circle
			(at 2.399995 0.399999 270)
			(size 0.3556 0.3556)
			(layers "B.Cu" "B.Mask" "B.Paste")
			(net "GND")
		)
		(pad "J3" smd circle
			(at 1.599997 0.399999 270)
			(size 0.3556 0.3556)
			(layers "B.Cu" "B.Mask" "B.Paste")
			(net "DDR0_32A_RAS_L")
		)
		(pad "J7" smd circle
			(at -1.599997 0.399999 270)
			(size 0.3556 0.3556)
			(layers "B.Cu" "B.Mask" "B.Paste")
			(net "DDR0_32A_CK0_P")
		)
		(pad "J8" smd circle
			(at -2.399995 0.399999 270)
			(size 0.3556 0.3556)
			(layers "B.Cu" "B.Mask" "B.Paste")
			(net "GND")
		)
		(pad "J9" smd circle
			(at -3.199994 0.399999 270)
			(size 0.3556 0.3556)
			(layers "B.Cu" "B.Mask" "B.Paste")
			(net "Net_500")
		)
		(pad "K1" smd circle
			(at 3.199994 1.199998 270)
			(size 0.3556 0.3556)
			(layers "B.Cu" "B.Mask" "B.Paste")
			(net "DDR0_32A_ODT0")
		)
		(pad "K2" smd circle
			(at 2.399995 1.199998 270)
			(size 0.3556 0.3556)
			(layers "B.Cu" "B.Mask" "B.Paste")
			(net "DDR_VDDQ")
		)
		(pad "K3" smd circle
			(at 1.599997 1.199998 270)
			(size 0.3556 0.3556)
			(layers "B.Cu" "B.Mask" "B.Paste")
			(net "DDR0_32A_CAS_L")
		)
		(pad "K7" smd circle
			(at -1.599997 1.199998 270)
			(size 0.3556 0.3556)
			(layers "B.Cu" "B.Mask" "B.Paste")
			(net "DDR0_32A_CK0_N")
		)
		(pad "K8" smd circle
			(at -2.399995 1.199998 270)
			(size 0.3556 0.3556)
			(layers "B.Cu" "B.Mask" "B.Paste")
			(net "DDR_VDDQ")
		)
		(pad "K9" smd circle
			(at -3.199994 1.199998 270)
			(size 0.3556 0.3556)
			(layers "B.Cu" "B.Mask" "B.Paste")
			(net "DDR0_32A_CKE0")
		)
		(pad "L1" smd circle
			(at 3.199994 1.999996 270)
			(size 0.3556 0.3556)
			(layers "B.Cu" "B.Mask" "B.Paste")
			(net "Net_498")
		)
		(pad "L2" smd circle
			(at 2.399995 1.999996 270)
			(size 0.3556 0.3556)
			(layers "B.Cu" "B.Mask" "B.Paste")
			(net "DDR0_32A_CS0_L")
		)
		(pad "L3" smd circle
			(at 1.599997 1.999996 270)
			(size 0.3556 0.3556)
			(layers "B.Cu" "B.Mask" "B.Paste")
			(net "DDR0_32A_WE_L")
		)
		(pad "L7" smd circle
			(at -1.599997 1.999996 270)
			(size 0.3556 0.3556)
			(layers "B.Cu" "B.Mask" "B.Paste")
			(net "DDR0_32A_A10")
		)
		(pad "L8" smd circle
			(at -2.399995 1.999996 270)
			(size 0.3556 0.3556)
			(layers "B.Cu" "B.Mask" "B.Paste")
			(net "12N3057")
		)
		(pad "L9" smd circle
			(at -3.199994 1.999996 270)
			(size 0.3556 0.3556)
			(layers "B.Cu" "B.Mask" "B.Paste")
			(net "Net_501")
		)
		(pad "M1" smd circle
			(at 3.199994 2.799994 270)
			(size 0.3556 0.3556)
			(layers "B.Cu" "B.Mask" "B.Paste")
			(net "GND")
		)
		(pad "M2" smd circle
			(at 2.399995 2.799994 270)
			(size 0.3556 0.3556)
			(layers "B.Cu" "B.Mask" "B.Paste")
			(net "DDR0_32A_BA0")
		)
		(pad "M3" smd circle
			(at 1.599997 2.799994 270)
			(size 0.3556 0.3556)
			(layers "B.Cu" "B.Mask" "B.Paste")
			(net "DDR0_32A_BA2")
		)
		(pad "M7" smd circle
			(at -1.599997 2.799994 270)
			(size 0.3556 0.3556)
			(layers "B.Cu" "B.Mask" "B.Paste")
			(net "Net_499")
		)
		(pad "M8" smd circle
			(at -2.399995 2.799994 270)
			(size 0.3556 0.3556)
			(layers "B.Cu" "B.Mask" "B.Paste")
			(net "DDR0_32A_VREF1B")
		)
		(pad "M9" smd circle
			(at -3.199994 2.799994 270)
			(size 0.3556 0.3556)
			(layers "B.Cu" "B.Mask" "B.Paste")
			(net "GND")
		)
		(pad "N1" smd circle
			(at 3.199994 3.599993 270)
			(size 0.3556 0.3556)
			(layers "B.Cu" "B.Mask" "B.Paste")
			(net "DDR_VDDQ")
		)
		(pad "N2" smd circle
			(at 2.399995 3.599993 270)
			(size 0.3556 0.3556)
			(layers "B.Cu" "B.Mask" "B.Paste")
			(net "DDR0_32A_A3")
		)
		(pad "N3" smd circle
			(at 1.599997 3.599993 270)
			(size 0.3556 0.3556)
			(layers "B.Cu" "B.Mask" "B.Paste")
			(net "DDR0_32A_A0")
		)
		(pad "N7" smd circle
			(at -1.599997 3.599993 270)
			(size 0.3556 0.3556)
			(layers "B.Cu" "B.Mask" "B.Paste")
			(net "DDR0_32A_A12")
		)
		(pad "N8" smd circle
			(at -2.399995 3.599993 270)
			(size 0.3556 0.3556)
			(layers "B.Cu" "B.Mask" "B.Paste")
			(net "DDR0_32A_BA1")
		)
		(pad "N9" smd circle
			(at -3.199994 3.599993 270)
			(size 0.3556 0.3556)
			(layers "B.Cu" "B.Mask" "B.Paste")
			(net "DDR_VDDQ")
		)
		(pad "P1" smd circle
			(at 3.199994 4.399991 270)
			(size 0.3556 0.3556)
			(layers "B.Cu" "B.Mask" "B.Paste")
			(net "GND")
		)
		(pad "P2" smd circle
			(at 2.399995 4.399991 270)
			(size 0.3556 0.3556)
			(layers "B.Cu" "B.Mask" "B.Paste")
			(net "DDR0_32A_A5")
		)
		(pad "P3" smd circle
			(at 1.599997 4.399991 270)
			(size 0.3556 0.3556)
			(layers "B.Cu" "B.Mask" "B.Paste")
			(net "DDR0_32A_A2")
		)
		(pad "P7" smd circle
			(at -1.599997 4.399991 270)
			(size 0.3556 0.3556)
			(layers "B.Cu" "B.Mask" "B.Paste")
			(net "DDR0_32A_A1")
		)
		(pad "P8" smd circle
			(at -2.399995 4.399991 270)
			(size 0.3556 0.3556)
			(layers "B.Cu" "B.Mask" "B.Paste")
			(net "DDR0_32A_A4")
		)
		(pad "P9" smd circle
			(at -3.199994 4.399991 270)
			(size 0.3556 0.3556)
			(layers "B.Cu" "B.Mask" "B.Paste")
			(net "GND")
		)
		(pad "R1" smd circle
			(at 3.199994 5.19999 270)
			(size 0.3556 0.3556)
			(layers "B.Cu" "B.Mask" "B.Paste")
			(net "DDR_VDDQ")
		)
		(pad "R2" smd circle
			(at 2.399995 5.19999 270)
			(size 0.3556 0.3556)
			(layers "B.Cu" "B.Mask" "B.Paste")
			(net "DDR0_32A_A7")
		)
		(pad "R3" smd circle
			(at 1.599997 5.19999 270)
			(size 0.3556 0.3556)
			(layers "B.Cu" "B.Mask" "B.Paste")
			(net "DDR0_32A_A9")
		)
		(pad "R7" smd circle
			(at -1.599997 5.19999 270)
			(size 0.3556 0.3556)
			(layers "B.Cu" "B.Mask" "B.Paste")
			(net "DDR0_32A_A11")
		)
		(pad "R8" smd circle
			(at -2.399995 5.19999 270)
			(size 0.3556 0.3556)
			(layers "B.Cu" "B.Mask" "B.Paste")
			(net "DDR0_32A_A6")
		)
		(pad "R9" smd circle
			(at -3.199994 5.19999 270)
			(size 0.3556 0.3556)
			(layers "B.Cu" "B.Mask" "B.Paste")
			(net "DDR_VDDQ")
		)
		(pad "T1" smd circle
			(at 3.199994 5.999988 270)
			(size 0.3556 0.3556)
			(layers "B.Cu" "B.Mask" "B.Paste")
			(net "GND")
		)
		(pad "T2" smd circle
			(at 2.399995 5.999988 270)
			(size 0.3556 0.3556)
			(layers "B.Cu" "B.Mask" "B.Paste")
			(net "DDR0_32A_DRAMRST_L")
		)
		(pad "T3" smd circle
			(at 1.599997 5.999988 270)
			(size 0.3556 0.3556)
			(layers "B.Cu" "B.Mask" "B.Paste")
			(net "DDR0_32A_A13")
		)
		(pad "T7" smd circle
			(at -1.599997 5.999988 270)
			(size 0.3556 0.3556)
			(layers "B.Cu" "B.Mask" "B.Paste")
			(net "DDR0_32A_A14")
		)
		(pad "T8" smd circle
			(at -2.399995 5.999988 270)
			(size 0.3556 0.3556)
			(layers "B.Cu" "B.Mask" "B.Paste")
			(net "DDR0_32A_A8")
		)
		(pad "T9" smd circle
			(at -3.199994 5.999988 270)
			(size 0.3556 0.3556)
			(layers "B.Cu" "B.Mask" "B.Paste")
			(net "GND")
		)
	)
)
